# S9S_MB_2U (Grand Teton) — schematic netlist excerpt (pin names and nets, part order shuffled) for the footprints in the layout excerpt that follows; sources: Cadence DE-HDL packaged netlist, KiCad conversion of 03242023_DA0F0TMBIJ0_F0T_Motherboard_J_brd_V01_OCP.brd

C508  Q_CAP  47UF 4V 20% X6S  pkg C0805  page 76 : A = PVCCFA_EHV_CPU0 ; B = GND
R1022  Q_RES  0 5% CHIP  pkg 0402LF  page 209 : A = CLK_25M_CK440_CPU1_R_DP ; B = CLK_25M_NSSC_CPU1_DP
C110  Q_CAP  0.047UF 25V 10% X7R  pkg C0402  page 210 : A = P3V3_AUX_CLK_GEN_VDD_CK440 ; B = GND

(kicad_pcb
	(version 20260206)
	(generator "pcbnew")
	(generator_version "10.0")
	(general
		(thickness 1.6)
		(legacy_teardrops no)
	)
	(paper "A4")
	(title_block
		(title "03242023_DA0F0TMBIJ0_F0T_Motherboard_J_brd_V01_OCP.brd")
		(comment 1 "Grand Teton / footprints 5152-5154 of 6105")
	)
	(layers
		(0 "F.Cu" signal "TOP")
		(4 "In1.Cu" signal "GND")
		(6 "In2.Cu" signal "IN1")
		(8 "In3.Cu" signal "GND1")
		(10 "In4.Cu" signal "IN2")
		(12 "In5.Cu" signal "GND2")
		(14 "In6.Cu" signal "IN3")
		(16 "In7.Cu" signal "GND3")
		(18 "In8.Cu" signal "VCC")
		(20 "In9.Cu" signal "VCC1")
		(22 "In10.Cu" signal "GND4")
		(24 "In11.Cu" signal "IN4")
		(26 "In12.Cu" signal "GND5")
		(28 "In13.Cu" signal "IN5")
		(30 "In14.Cu" signal "GND6")
		(32 "In15.Cu" signal "IN6")
		(34 "In16.Cu" signal "GND7")
		(2 "B.Cu" signal "BOTTOM")
		(9 "F.Adhes" user "F.Adhesive")
		(11 "B.Adhes" user "B.Adhesive")
		(13 "F.Paste" user "Package Geometry/Pastemask Top")
		(15 "B.Paste" user "Package Geometry/Pastemask Bottom")
		(5 "F.SilkS" user "Ref Des/Silkscreen Top")
		(7 "B.SilkS" user "Ref Des/Silkscreen Bottom")
		(1 "F.Mask" user "Board Geometry/Soldermask Top")
		(3 "B.Mask" user "Board Geometry/Soldermask Bottom")
		(17 "Dwgs.User" user "User.Drawings")
		(19 "Cmts.User" user "User.Comments")
		(21 "Eco1.User" user "User.Eco1")
		(23 "Eco2.User" user "User.Eco2")
		(25 "Edge.Cuts" user "Board Geometry/Outline")
		(27 "Margin" user)
		(31 "F.CrtYd" user "Package Geometry/Place Bound Top")
		(29 "B.CrtYd" user "Package Geometry/Place Bound Bottom")
		(35 "F.Fab" user "Ref Des/Assembly Top")
		(33 "B.Fab" user "Ref Des/Assembly Bottom")
	)
	(footprint ""
		(layer "B.Cu")
		(at 236.182154 -134.048754 180)
		(property "Reference" "R1022"
			(at 0 0 0)
			(layer "B.SilkS")
			(hide yes)
			(effects
				(font
					(size 1.27 1.27)
				)
				(justify mirror)
			)
		)
		(property "Value" ""
			(at 0 0 0)
			(layer "B.Fab")
			(effects
				(font
					(size 1.27 1.27)
				)
				(justify mirror)
			)
		)
		(duplicate_pad_numbers_are_jumpers no)
		(fp_line
			(start 0.7874 -0.154686)
			(end 0.7874 -0.4064)
			(stroke
				(width 0.1524)
				(type default)
			)
			(layer "B.SilkS")
		)
		(fp_line
			(start 0.7874 -0.4064)
			(end -0.7874 -0.4064)
			(stroke
				(width 0.1524)
				(type default)
			)
			(layer "B.SilkS")
		)
		(fp_line
			(start -0.241046 0.4064)
			(end 0.632714 0.4064)
			(stroke
				(width 0.1524)
				(type default)
			)
			(layer "B.SilkS")
		)
		(fp_line
			(start -0.7874 0.4064)
			(end -0.576326 0.4064)
			(stroke
				(width 0.1524)
				(type default)
			)
			(layer "B.SilkS")
		)
		(fp_line
			(start -0.7874 -0.4064)
			(end -0.7874 0.4064)
			(stroke
				(width 0.1524)
				(type default)
			)
			(layer "B.SilkS")
		)
		(fp_line
			(start 0.67945 0.3048)
			(end 0.67945 -0.305054)
			(stroke
				(width 0.1)
				(type default)
			)
			(layer "B.Fab")
		)
		(fp_line
			(start 0.67945 -0.305054)
			(end 0.12065 -0.305054)
			(stroke
				(width 0.1)
				(type default)
			)
			(layer "B.Fab")
		)
		(fp_line
			(start 0.12065 0.3048)
			(end 0.67945 0.3048)
			(stroke
				(width 0.1)
				(type default)
			)
			(layer "B.Fab")
		)
		(fp_line
			(start 0.12065 0.2794)
			(end 0.12065 0.3048)
			(stroke
				(width 0.1)
				(type default)
			)
			(layer "B.Fab")
		)
		(fp_line
			(start 0.12065 -0.2794)
			(end -0.12065 -0.2794)
			(stroke
				(width 0.1)
				(type default)
			)
			(layer "B.Fab")
		)
		(fp_line
			(start 0.12065 -0.305054)
			(end 0.12065 -0.2794)
			(stroke
				(width 0.1)
				(type default)
			)
			(layer "B.Fab")
		)
		(fp_line
			(start -0.120396 0.3048)
			(end -0.120396 0.2794)
			(stroke
				(width 0.1)
				(type default)
			)
			(layer "B.Fab")
		)
		(fp_line
			(start -0.120396 0.2794)
			(end 0.12065 0.2794)
			(stroke
				(width 0.1)
				(type default)
			)
			(layer "B.Fab")
		)
		(fp_line
			(start -0.12065 -0.2794)
			(end -0.12065 -0.3048)
			(stroke
				(width 0.1)
				(type default)
			)
			(layer "B.Fab")
		)
		(fp_line
			(start -0.12065 -0.3048)
			(end -0.67945 -0.3048)
			(stroke
				(width 0.1)
				(type default)
			)
			(layer "B.Fab")
		)
		(fp_line
			(start -0.67945 0.3048)
			(end -0.120396 0.3048)
			(stroke
				(width 0.1)
				(type default)
			)
			(layer "B.Fab")
		)
		(fp_line
			(start -0.67945 -0.3048)
			(end -0.67945 0.3048)
			(stroke
				(width 0.1)
				(type default)
			)
			(layer "B.Fab")
		)
		(pad "1" smd rect
			(at 0.40005 0 180)
			(size 0.4572 0.508)
			(layers "B.Cu" "B.Mask" "B.Paste")
			(net "CLK_25M_CK440_CPU1_R_DP")
		)
		(pad "2" smd rect
			(at -0.40005 0 180)
			(size 0.4572 0.508)
			(layers "B.Cu" "B.Mask" "B.Paste")
			(net "CLK_25M_NSSC_CPU1_DP")
		)
	)
	(footprint ""
		(layer "B.Cu")
		(at 258.953 -96.738948)
		(property "Reference" "C110"
			(at 0 0 0)
			(layer "B.SilkS")
			(hide yes)
			(effects
				(font
					(size 1.27 1.27)
				)
				(justify mirror)
			)
		)
		(property "Value" ""
			(at 0 0 0)
			(layer "B.Fab")
			(effects
				(font
					(size 1.27 1.27)
				)
				(justify mirror)
			)
		)
		(duplicate_pad_numbers_are_jumpers no)
		(fp_line
			(start -0.7874 -0.4064)
			(end -0.7874 0.4064)
			(stroke
				(width 0.1524)
				(type default)
			)
			(layer "B.SilkS")
		)
		(fp_line
			(start -0.7874 0.4064)
			(end 0.7874 0.4064)
			(stroke
				(width 0.1524)
				(type default)
			)
			(layer "B.SilkS")
		)
		(fp_line
			(start 0.7874 -0.4064)
			(end -0.7874 -0.4064)
			(stroke
				(width 0.1524)
				(type default)
			)
			(layer "B.SilkS")
		)
		(fp_line
			(start 0.7874 0.4064)
			(end 0.7874 -0.4064)
			(stroke
				(width 0.1524)
				(type default)
			)
			(layer "B.SilkS")
		)
		(fp_line
			(start -0.67945 -0.3048)
			(end -0.67945 0.3048)
			(stroke
				(width 0.1)
				(type default)
			)
			(layer "B.Fab")
		)
		(fp_line
			(start -0.67945 0.3048)
			(end -0.120396 0.3048)
			(stroke
				(width 0.1)
				(type default)
			)
			(layer "B.Fab")
		)
		(fp_line
			(start -0.12065 -0.3048)
			(end -0.67945 -0.3048)
			(stroke
				(width 0.1)
				(type default)
			)
			(layer "B.Fab")
		)
		(fp_line
			(start -0.12065 -0.2794)
			(end -0.12065 -0.3048)
			(stroke
				(width 0.1)
				(type default)
			)
			(layer "B.Fab")
		)
		(fp_line
			(start -0.120396 0.2794)
			(end 0.12065 0.2794)
			(stroke
				(width 0.1)
				(type default)
			)
			(layer "B.Fab")
		)
		(fp_line
			(start -0.120396 0.3048)
			(end -0.120396 0.2794)
			(stroke
				(width 0.1)
				(type default)
			)
			(layer "B.Fab")
		)
		(fp_line
			(start 0.12065 -0.305054)
			(end 0.12065 -0.2794)
			(stroke
				(width 0.1)
				(type default)
			)
			(layer "B.Fab")
		)
		(fp_line
			(start 0.12065 -0.2794)
			(end -0.12065 -0.2794)
			(stroke
				(width 0.1)
				(type default)
			)
			(layer "B.Fab")
		)
		(fp_line
			(start 0.12065 0.2794)
			(end 0.12065 0.3048)
			(stroke
				(width 0.1)
				(type default)
			)
			(layer "B.Fab")
		)
		(fp_line
			(start 0.12065 0.3048)
			(end 0.67945 0.3048)
			(stroke
				(width 0.1)
				(type default)
			)
			(layer "B.Fab")
		)
		(fp_line
			(start 0.67945 -0.305054)
			(end 0.12065 -0.305054)
			(stroke
				(width 0.1)
				(type default)
			)
			(layer "B.Fab")
		)
		(fp_line
			(start 0.67945 0.3048)
			(end 0.67945 -0.305054)
			(stroke
				(width 0.1)
				(type default)
			)
			(layer "B.Fab")
		)
		(pad "1" smd circle
			(at 0.40005 0 180)
			(size 0 0)
			(layers "B.Cu" "B.Mask" "B.Paste")
			(net "P3V3_AUX_CLK_GEN_VDD_CK440")
		)
		(pad "2" smd circle
			(at -0.40005 0 180)
			(size 0 0)
			(layers "B.Cu" "B.Mask" "B.Paste")
			(net "GND")
		)
	)
	(footprint ""
		(layer "B.Cu")
		(at 355.826822 -210.19389 180)
		(property "Reference" "C508"
			(at 0 0 0)
			(layer "B.SilkS")
			(hide yes)
			(effects
				(font
					(size 1.27 1.27)
				)
				(justify mirror)
			)
		)
		(property "Value" ""
			(at 0 0 0)
			(layer "B.Fab")
			(effects
				(font
					(size 1.27 1.27)
				)
				(justify mirror)
			)
		)
		(duplicate_pad_numbers_are_jumpers no)
		(fp_line
			(start 1.524 0.762)
			(end 1.524 -0.762)
			(stroke
				(width 0.1524)
				(type default)
			)
			(layer "B.SilkS")
		)
		(fp_line
			(start 1.524 -0.762)
			(end -1.524 -0.762)
			(stroke
				(width 0.1524)
				(type default)
			)
			(layer "B.SilkS")
		)
		(fp_line
			(start -1.524 0.762)
			(end 1.524 0.762)
			(stroke
				(width 0.1524)
				(type default)
			)
			(layer "B.SilkS")
		)
		(fp_line
			(start -1.524 -0.762)
			(end -1.524 0.762)
			(stroke
				(width 0.1524)
				(type default)
			)
			(layer "B.SilkS")
		)
		(fp_line
			(start 1.1049 0.724916)
			(end -1.1049 0.724916)
			(stroke
				(width 0.1)
				(type default)
			)
			(layer "B.Fab")
		)
		(fp_line
			(start 1.1049 -0.724916)
			(end 1.1049 0.724916)
			(stroke
				(width 0.1)
				(type default)
			)
			(layer "B.Fab")
		)
		(fp_line
			(start -1.1049 0.724916)
			(end -1.1049 -0.724916)
			(stroke
				(width 0.1)
				(type default)
			)
			(layer "B.Fab")
		)
		(fp_line
			(start -1.1049 -0.724916)
			(end 1.1049 -0.724916)
			(stroke
				(width 0.1)
				(type default)
			)
			(layer "B.Fab")
		)
		(pad "1" smd rect
			(at 0.889 0 180)
			(size 1.016 1.27)
			(layers "B.Cu" "B.Mask" "B.Paste")
			(net "PVCCFA_EHV_CPU0")
		)
		(pad "2" smd rect
			(at -0.889 0 180)
			(size 1.016 1.27)
			(layers "B.Cu" "B.Mask" "B.Paste")
			(net "GND")
		)
	)
)
